(kicad_pcb
	(version 20260206)
	(generator "pcbnew")
	(generator_version "10.0")
	(general
		(thickness 1.6)
		(legacy_teardrops no)
	)
	(paper "A4")
	(title_block
		(title "01162023_DA0F0TEBIF0_F0T_Expander_BD_F_brd_V02_OCP.brd")
		(comment 1 "Grand Teton / footprints 3767-3769 of 9728")
	)
	(layers
		(0 "F.Cu" signal "TOP")
		(4 "In1.Cu" signal "GND")
		(6 "In2.Cu" signal "VCC")
		(8 "In3.Cu" signal "VCC1")
		(10 "In4.Cu" signal "GND1")
		(12 "In5.Cu" signal "IN1")
		(14 "In6.Cu" signal "GND2")
		(16 "In7.Cu" signal "IN2")
		(18 "In8.Cu" signal "GND3")
		(20 "In9.Cu" signal "IN3")
		(22 "In10.Cu" signal "GND4")
		(24 "In11.Cu" signal "IN4")
		(26 "In12.Cu" signal "GND5")
		(28 "In13.Cu" signal "IN5")
		(30 "In14.Cu" signal "GND6")
		(32 "In15.Cu" signal "IN6")
		(34 "In16.Cu" signal "GND7")
		(2 "B.Cu" signal "BOTTOM")
		(9 "F.Adhes" user "F.Adhesive")
		(11 "B.Adhes" user "B.Adhesive")
		(13 "F.Paste" user "Package Geometry/Pastemask Top")
		(15 "B.Paste" user "Package Geometry/Pastemask Bottom")
		(5 "F.SilkS" user "Ref Des/Silkscreen Top")
		(7 "B.SilkS" user "Ref Des/Silkscreen Bottom")
		(1 "F.Mask" user "Board Geometry/Soldermask Top")
		(3 "B.Mask" user "Board Geometry/Soldermask Bottom")
		(17 "Dwgs.User" user "User.Drawings")
		(19 "Cmts.User" user "User.Comments")
		(21 "Eco1.User" user "User.Eco1")
		(23 "Eco2.User" user "User.Eco2")
		(25 "Edge.Cuts" user "Board Geometry/Outline")
		(27 "Margin" user)
		(31 "F.CrtYd" user "Package Geometry/Place Bound Top")
		(29 "B.CrtYd" user "Package Geometry/Place Bound Bottom")
		(35 "F.Fab" user "Ref Des/Assembly Top")
		(33 "B.Fab" user "Ref Des/Assembly Bottom")
	)
	(footprint ""
		(layer "F.Cu")
		(at 36.534344 -250.070874 -90)
		(property "Reference" "R1158"
			(at 0 0 270)
			(layer "F.SilkS")
			(hide yes)
			(effects
				(font
					(size 1.27 1.27)
				)
			)
		)
		(property "Value" ""
			(at 0 0 270)
			(layer "F.Fab")
			(effects
				(font
					(size 1.27 1.27)
				)
			)
		)
		(duplicate_pad_numbers_are_jumpers no)
		(fp_line
			(start -0.7874 0.4064)
			(end -0.7874 -0.4064)
			(stroke
				(width 0.1524)
				(type default)
			)
			(layer "F.SilkS")
		)
		(fp_line
			(start 0.7874 0.4064)
			(end -0.7874 0.4064)
			(stroke
				(width 0.1524)
				(type default)
			)
			(layer "F.SilkS")
		)
		(fp_line
			(start -0.7874 -0.4064)
			(end 0.7874 -0.4064)
			(stroke
				(width 0.1524)
				(type default)
			)
			(layer "F.SilkS")
		)
		(fp_line
			(start 0.7874 -0.4064)
			(end 0.7874 0.4064)
			(stroke
				(width 0.1524)
				(type default)
			)
			(layer "F.SilkS")
		)
		(fp_line
			(start -0.67945 0.3048)
			(end -0.67945 -0.305054)
			(stroke
				(width 0.1)
				(type default)
			)
			(layer "F.Fab")
		)
		(fp_line
			(start -0.12065 0.3048)
			(end -0.67945 0.3048)
			(stroke
				(width 0.1)
				(type default)
			)
			(layer "F.Fab")
		)
		(fp_line
			(start 0.120396 0.3048)
			(end 0.120396 0.2794)
			(stroke
				(width 0.1)
				(type default)
			)
			(layer "F.Fab")
		)
		(fp_line
			(start 0.67945 0.3048)
			(end 0.120396 0.3048)
			(stroke
				(width 0.1)
				(type default)
			)
			(layer "F.Fab")
		)
		(fp_line
			(start -0.12065 0.2794)
			(end -0.12065 0.3048)
			(stroke
				(width 0.1)
				(type default)
			)
			(layer "F.Fab")
		)
		(fp_line
			(start 0.120396 0.2794)
			(end -0.12065 0.2794)
			(stroke
				(width 0.1)
				(type default)
			)
			(layer "F.Fab")
		)
		(fp_line
			(start -0.12065 -0.2794)
			(end 0.12065 -0.2794)
			(stroke
				(width 0.1)
				(type default)
			)
			(layer "F.Fab")
		)
		(fp_line
			(start 0.12065 -0.2794)
			(end 0.12065 -0.3048)
			(stroke
				(width 0.1)
				(type default)
			)
			(layer "F.Fab")
		)
		(fp_line
			(start 0.12065 -0.3048)
			(end 0.67945 -0.3048)
			(stroke
				(width 0.1)
				(type default)
			)
			(layer "F.Fab")
		)
		(fp_line
			(start 0.67945 -0.3048)
			(end 0.67945 0.3048)
			(stroke
				(width 0.1)
				(type default)
			)
			(layer "F.Fab")
		)
		(fp_line
			(start -0.67945 -0.305054)
			(end -0.12065 -0.305054)
			(stroke
				(width 0.1)
				(type default)
			)
			(layer "F.Fab")
		)
		(fp_line
			(start -0.12065 -0.305054)
			(end -0.12065 -0.2794)
			(stroke
				(width 0.1)
				(type default)
			)
			(layer "F.Fab")
		)
		(pad "1" smd circle
			(at -0.40005 0 270)
			(size 0 0)
			(layers "F.Cu" "F.Mask" "F.Paste")
			(net "PEX0_MODE_SEL6")
		)
		(pad "2" smd circle
			(at 0.40005 0 270)
			(size 0 0)
			(layers "F.Cu" "F.Mask" "F.Paste")
			(net "P1V8_PEX")
		)
	)
	(footprint ""
		(layer "F.Cu")
		(at 10.716514 -277.814278 180)
		(property "Reference" "C625"
			(at 0 0 180)
			(layer "F.SilkS")
			(hide yes)
			(effects
				(font
					(size 1.27 1.27)
				)
			)
		)
		(property "Value" ""
			(at 0 0 180)
			(layer "F.Fab")
			(effects
				(font
					(size 1.27 1.27)
				)
			)
		)
		(duplicate_pad_numbers_are_jumpers no)
		(fp_line
			(start 0.7874 0.4064)
			(end -0.7874 0.4064)
			(stroke
				(width 0.1524)
				(type default)
			)
			(layer "F.SilkS")
		)
		(fp_line
			(start 0.7874 -0.4064)
			(end 0.7874 0.4064)
			(stroke
				(width 0.1524)
				(type default)
			)
			(layer "F.SilkS")
		)
		(fp_line
			(start -0.7874 0.4064)
			(end -0.7874 -0.4064)
			(stroke
				(width 0.1524)
				(type default)
			)
			(layer "F.SilkS")
		)
		(fp_line
			(start -0.7874 -0.4064)
			(end 0.7874 -0.4064)
			(stroke
				(width 0.1524)
				(type default)
			)
			(layer "F.SilkS")
		)
		(fp_line
			(start 0.67945 0.3048)
			(end 0.120396 0.3048)
			(stroke
				(width 0.1)
				(type default)
			)
			(layer "F.Fab")
		)
		(fp_line
			(start 0.67945 -0.3048)
			(end 0.67945 0.3048)
			(stroke
				(width 0.1)
				(type default)
			)
			(layer "F.Fab")
		)
		(fp_line
			(start 0.12065 -0.2794)
			(end 0.12065 -0.3048)
			(stroke
				(width 0.1)
				(type default)
			)
			(layer "F.Fab")
		)
		(fp_line
			(start 0.12065 -0.3048)
			(end 0.67945 -0.3048)
			(stroke
				(width 0.1)
				(type default)
			)
			(layer "F.Fab")
		)
		(fp_line
			(start 0.120396 0.3048)
			(end 0.120396 0.2794)
			(stroke
				(width 0.1)
				(type default)
			)
			(layer "F.Fab")
		)
		(fp_line
			(start 0.120396 0.2794)
			(end -0.12065 0.2794)
			(stroke
				(width 0.1)
				(type default)
			)
			(layer "F.Fab")
		)
		(fp_line
			(start -0.12065 0.3048)
			(end -0.67945 0.3048)
			(stroke
				(width 0.1)
				(type default)
			)
			(layer "F.Fab")
		)
		(fp_line
			(start -0.12065 0.2794)
			(end -0.12065 0.3048)
			(stroke
				(width 0.1)
				(type default)
			)
			(layer "F.Fab")
		)
		(fp_line
			(start -0.12065 -0.2794)
			(end 0.12065 -0.2794)
			(stroke
				(width 0.1)
				(type default)
			)
			(layer "F.Fab")
		)
		(fp_line
			(start -0.12065 -0.305054)
			(end -0.12065 -0.2794)
			(stroke
				(width 0.1)
				(type default)
			)
			(layer "F.Fab")
		)
		(fp_line
			(start -0.67945 0.3048)
			(end -0.67945 -0.305054)
			(stroke
				(width 0.1)
				(type default)
			)
			(layer "F.Fab")
		)
		(fp_line
			(start -0.67945 -0.305054)
			(end -0.12065 -0.305054)
			(stroke
				(width 0.1)
				(type default)
			)
			(layer "F.Fab")
		)
		(pad "1" smd circle
			(at -0.40005 0 180)
			(size 0 0)
			(layers "F.Cu" "F.Mask" "F.Paste")
			(net "P3V3_AUX")
		)
		(pad "2" smd circle
			(at 0.40005 0 180)
			(size 0 0)
			(layers "F.Cu" "F.Mask" "F.Paste")
			(net "GND")
		)
	)
	(footprint ""
		(layer "F.Cu")
		(at 224.514664 -207.02016 90)
		(property "Reference" "R5715"
			(at 0 0 90)
			(layer "F.SilkS")
			(hide yes)
			(effects
				(font
					(size 1.27 1.27)
				)
			)
		)
		(property "Value" ""
			(at 0 0 90)
			(layer "F.Fab")
			(effects
				(font
					(size 1.27 1.27)
				)
			)
		)
		(duplicate_pad_numbers_are_jumpers no)
		(fp_line
			(start 0.7874 -0.4064)
			(end 0.7874 0.4064)
			(stroke
				(width 0.1524)
				(type default)
			)
			(layer "F.SilkS")
		)
		(fp_line
			(start -0.7874 -0.4064)
			(end 0.7874 -0.4064)
			(stroke
				(width 0.1524)
				(type default)
			)
			(layer "F.SilkS")
		)
		(fp_line
			(start 0.7874 0.4064)
			(end -0.7874 0.4064)
			(stroke
				(width 0.1524)
				(type default)
			)
			(layer "F.SilkS")
		)
		(fp_line
			(start -0.7874 0.4064)
			(end -0.7874 -0.4064)
			(stroke
				(width 0.1524)
				(type default)
			)
			(layer "F.SilkS")
		)
		(fp_line
			(start -0.12065 -0.305054)
			(end -0.12065 -0.2794)
			(stroke
				(width 0.1)
				(type default)
			)
			(layer "F.Fab")
		)
		(fp_line
			(start -0.67945 -0.305054)
			(end -0.12065 -0.305054)
			(stroke
				(width 0.1)
				(type default)
			)
			(layer "F.Fab")
		)
		(fp_line
			(start 0.67945 -0.3048)
			(end 0.67945 0.3048)
			(stroke
				(width 0.1)
				(type default)
			)
			(layer "F.Fab")
		)
		(fp_line
			(start 0.12065 -0.3048)
			(end 0.67945 -0.3048)
			(stroke
				(width 0.1)
				(type default)
			)
			(layer "F.Fab")
		)
		(fp_line
			(start 0.12065 -0.2794)
			(end 0.12065 -0.3048)
			(stroke
				(width 0.1)
				(type default)
			)
			(layer "F.Fab")
		)
		(fp_line
			(start -0.12065 -0.2794)
			(end 0.12065 -0.2794)
			(stroke
				(width 0.1)
				(type default)
			)
			(layer "F.Fab")
		)
		(fp_line
			(start 0.120396 0.2794)
			(end -0.12065 0.2794)
			(stroke
				(width 0.1)
				(type default)
			)
			(layer "F.Fab")
		)
		(fp_line
			(start -0.12065 0.2794)
			(end -0.12065 0.3048)
			(stroke
				(width 0.1)
				(type default)
			)
			(layer "F.Fab")
		)
		(fp_line
			(start 0.67945 0.3048)
			(end 0.120396 0.3048)
			(stroke
				(width 0.1)
				(type default)
			)
			(layer "F.Fab")
		)
		(fp_line
			(start 0.120396 0.3048)
			(end 0.120396 0.2794)
			(stroke
				(width 0.1)
				(type default)
			)
			(layer "F.Fab")
		)
		(fp_line
			(start -0.12065 0.3048)
			(end -0.67945 0.3048)
			(stroke
				(width 0.1)
				(type default)
			)
			(layer "F.Fab")
		)
		(fp_line
			(start -0.67945 0.3048)
			(end -0.67945 -0.305054)
			(stroke
				(width 0.1)
				(type default)
			)
			(layer "F.Fab")
		)
		(pad "1" smd circle
			(at -0.40005 0 90)
			(size 0 0)
			(layers "F.Cu" "F.Mask" "F.Paste")
			(net "RST_SMB_FPGA_R_N")
		)
		(pad "2" smd circle
			(at 0.40005 0 90)
			(size 0 0)
			(layers "F.Cu" "F.Mask" "F.Paste")
			(net "RST_SMB_FPGA_N")
		)
	)
)
